FILE_TYPE = CONNECTIVITY;
{Allegro Design Entry HDL 17.2-2016 S081 (4005846) 1/11/2022}
"PAGE_NUMBER" = 146;
0"NC";
1"P3V3_OCP_V3_2\g";
2"P3V3_OCP_V3_2\g";
3"P3V3_OCP_V3_2\g";
4"P3V3_OCP_V3_2\g";
5"P12V_OCP_V3_2\g";
6"P12V_OCP_V3_2\g";
7"GND\g";
8"GND\g";
9"GND\g";
10"GND\g";
11"GND\g";
12"GND\g";
13"GND\g";
14"GND\g";
15"GND\g";
16"P5E_CPU1_PE1_RX_DP<15:0>";
17"P5E_CPU1_PE1_RX_DN<15:0>";
18"P5E_CPU1_PE1_TX_C_DN<15:0>";
19"P5E_CPU1_PE1_TX_C_DP<15:0>";
20"CLK_100M_OCP_V3_2_D_DN";
21"CLK_50M_NCSI_OCP_V3_2_ISO";
22"SMB_OCP_V3_2_3V3AUX_BUF_SCL";
23"SMB_OCP_V3_2_3V3AUX_BUF_SDA";
24"RST_SMB_OCP_V3_2_N";
25"SMB_OCP_V3_2_3V3AUX_BUF_R_SCL";
26"SMB_OCP_V3_2_3V3AUX_BUF_R_SDA";
27"OCP_V3_1_PRSNTA_R_N";
28"RST_PERST1_OCP_V3_2_N";
29"OCP_V3_2_PRSNT2_R_N";
30"CLK_100M_OCP_V3_2_D_DP";
31"CLK_100M_OCP_V3_2_B_DP";
32"CLK_100M_OCP_V3_2_B_DN";
33"P5E_CPU1_PE1_RX_DN<14>";
34"P5E_CPU1_PE1_RX_DP<14>";
35"P5E_CPU1_PE1_TX_C_DN<15>";
36"P5E_CPU1_PE1_TX_C_DP<15>";
37"TP_OCP_V3_2_B68";
38"TP_OCP_V3_2_B69";
39"FM_OCP_V3_2_PWR_GOOD"CDS_PHYS_NET_NAME"FM_OCP_SFF_PWR_GOOD";
40"CLK_100M_OCP_V3_2_A_DP";
41"OCP_V3_2_BIF0_R_N";
42"OCP_V3_2_AUX_PWR_EN";
43"OCP_V3_2_AUX_PWR_EN_R";
44"RST_PERST0_OCP_V3_2_N";
45"OCP_V3_2_BIF2_R_N";
46"CLK_100M_OCP_V3_2_A_DN";
47"OCP_V3_2_BIF1_R_N";
48"NCSI_OCP_V3_2_RXD1";
49"CLK_100M_OCP_V3_2_C_DN";
50"CLK_100M_OCP_V3_2_C_DP";
51"NCSI_OCP_V3_2_CRS_DV";
52"NCSI_OCP_V3_2_TXD0";
53"NCSI_OCP_V3_2_TXD1";
54"NCSI_OCP_V3_2_TX_EN";
55"P5E_CPU1_PE1_TX_C_DP<0>";
56"OCP_V3_2_AUX_PWR_EN"CDS_PHYS_NET_NAME"OCP_SFF_AUX_PWR_EN";
57"OCP_V3_2_PWRBRK_N";
58"USB2_5_R1_DP";
59"P5E_CPU1_PE1_RX_DP<11>";
60"P5E_CPU1_PE1_RX_DN<12>";
61"OCP_V3_2_ID1";
62"OCP_V3_2_ID0";
63"OCP_V3_2_PRSNT3_R_N";
64"P5E_CPU1_PE1_TX_C_DP<3>";
65"P5E_CPU1_PE1_TX_C_DN<3>";
66"P5E_CPU1_PE1_TX_C_DP<1>"$PNN"P5E_CPU1_PE1_TX_C_DP<1>";
67"P5E_CPU1_PE1_TX_C_DN<1>"$PNN"P5E_CPU1_PE1_TX_C_DN<1>";
68"P5E_CPU1_PE1_TX_C_DN<0>";
69"P5E_CPU1_PE1_RX_DP<3>";
70"P5E_CPU1_PE1_TX_C_DN<14>";
71"P5E_CPU1_PE1_TX_C_DP<14>";
72"P5E_CPU1_PE1_TX_C_DP<13>";
73"P5E_CPU1_PE1_TX_C_DN<13>";
74"P5E_CPU1_PE1_RX_DN<3>";
75"P5E_CPU1_PE1_RX_DP<4>";
76"P5E_CPU1_PE1_RX_DP<5>";
77"P5E_CPU1_PE1_RX_DN<6>";
78"P5E_CPU1_PE1_TX_C_DP<8>";
79"P5E_CPU1_PE1_RX_DN<13>";
80"P5E_CPU1_PE1_RX_DP<13>";
81"P5E_CPU1_PE1_RX_DP<9>";
82"P5E_CPU1_PE1_RX_DN<10>";
83"USB2_5_R1_DN";
84"P5E_CPU1_PE1_RX_DN<8>";
85"OCP_V3_2_PRSNT1_R_N";
86"P5E_CPU1_PE1_RX_DN<15>";
87"P5E_CPU1_PE1_RX_DP<15>";
88"USB2_5_DP";
89"USB2_5_DN";
90"P5E_CPU1_PE1_RX_DN<11>";
91"P5E_CPU1_PE1_RX_DP<10>";
92"SGPIO_OCP_V3_2_LD_N";
93"SGPIO_OCP_V3_2_DATAIN";
94"SGPIO_OCP_V3_2_DATAOUT";
95"SGPIO_OCP_V3_2_CLK";
96"NCSI_OCP_V3_2_RXD0";
97"SGPIO_OCP_V3_2_CLK";
98"SGPIO_OCP_V3_2_DATAOUT";
99"SGPIO_OCP_V3_2_LD_N";
100"OCP_V3_2_MAIN_PWR_EN_R";
101"FM_OCP_V3_2_PWR_GOOD";
102"OCP_V3_2_ISO_BIF1_EN";
103"OCP_V3_2_ISO_BIF0_EN";
104"OCP_V3_2_MAIN_PWR_EN";
105"OCP_V3_2_ID0";
106"OCP_V3_2_ISO2_RBT_ARB_OUT";
107"OCP_V3_2_ISO1_RBT_ARB_IN";
108"IRQ_LVC3_OCP_V3_2_WAKE_N";
109"RST_PERST3_OCP_V3_2_N";
110"RST_PERST2_OCP_V3_2_N";
111"P5E_CPU1_PE1_TX_C_DP<2>";
112"P5E_CPU1_PE1_TX_C_DN<2>";
113"OCP_V3_2_MAIN_PWR_EN"CDS_PHYS_NET_NAME"OCP_SFF_MAIN_PWR_EN";
114"SGPIO_OCP_V3_2_DATAIN";
115"P5E_CPU1_PE1_RX_DP<1>";
116"P5E_CPU1_PE1_TX_C_DN<7>"$PNN"P5E_CPU1_PE1_TX_C_DN<7>";
117"P5E_CPU1_PE1_TX_C_DP<7>";
118"OCP_V3_2_PRSNT0_R_N";
119"P5E_CPU1_PE1_TX_C_DN<11>";
120"P5E_CPU1_PE1_TX_C_DP<10>";
121"P5E_CPU1_PE1_TX_C_DN<9>"$PNN"P5E_CPU1_PE1_TX_C_DN<9>";
122"P5E_CPU1_PE1_TX_C_DN<5>"$PNN"P5E_CPU1_PE1_TX_C_DN<5>";
123"P5E_CPU1_PE1_TX_C_DP<4>";
124"P5E_CPU1_PE1_TX_C_DP<9>";
125"P5E_CPU1_PE1_TX_C_DN<4>";
126"P5E_CPU1_PE1_TX_C_DP<5>";
127"P5E_CPU1_PE1_TX_C_DN<6>";
128"P5E_CPU1_PE1_TX_C_DN<8>";
129"P5E_CPU1_PE1_TX_C_DN<10>";
130"P5E_CPU1_PE1_TX_C_DP<12>";
131"P5E_CPU1_PE1_TX_C_DP<11>";
132"P5E_CPU1_PE1_TX_C_DP<6>";
133"P5E_CPU1_PE1_RX_DN<9>";
134"P5E_CPU1_PE1_RX_DP<12>";
135"P5E_CPU1_PE1_TX_C_DN<12>";
136"P5E_CPU1_PE1_RX_DP<7>";
137"P5E_CPU1_PE1_RX_DN<7>";
138"P5E_CPU1_PE1_RX_DN<0>";
139"OCP_V3_2_ID1";
140"P5E_CPU1_PE1_RX_DP<0>";
141"P5E_CPU1_PE1_RX_DN<1>";
142"P5E_CPU1_PE1_RX_DN<2>";
143"P5E_CPU1_PE1_RX_DP<2>";
144"P5E_CPU1_PE1_RX_DN<4>";
145"P5E_CPU1_PE1_RX_DN<5>";
146"P5E_CPU1_PE1_RX_DP<6>";
147"P5E_CPU1_PE1_RX_DP<8>";
148"OCP_V3_2_ISO_BIF2_EN";
%"UNIVERSAL_GND"
"1","(5325,225)","0","logical_power","I124";
;
CDS_LIB"logical_power"
HDL_POWER"GND";
"A"9;
%"UNIVERSAL_GND"
"1","(3675,225)","0","logical_power","I144";
;
CDS_LIB"logical_power"
HDL_POWER"GND";
"A"11;
%"Q_RES"
"1","(6875,775)","0","pure_quanta","I147";
;
PART_NUMBER"CS00002JB13"
VALUE"0"
TOLERANCE"5%"
PACK_TYPE"0402LF"
$LOCATION"R3178"
CDS_LIB"pure_quanta"
WATTAGE"1/16W"
MATERIAL"CHIP"
CDS_LOCATION"R3178"
$SEC"1"
CDS_SEC"1";
"B"
$PN"2"88;
"A"
$PN"1"58;
%"Q_RES"
"1","(6875,825)","0","pure_quanta","I148";
;
PART_NUMBER"CS00002JB13"
WATTAGE"1/16W"
TOLERANCE"5%"
VALUE"0"
PACK_TYPE"0402LF"
MATERIAL"CHIP"
$LOCATION"R3177"
CDS_LIB"pure_quanta"
CDS_LOCATION"R3177"
$SEC"1"
CDS_SEC"1";
"B"
$PN"2"89;
"A"
$PN"1"83;
%"UNIVERSAL_GND"
"1","(7975,3400)","0","logical_power","I151";
;
CDS_LIB"logical_power"
HDL_POWER"GND"
ROOM"IO_SLOT";
"A"10;
%"Q_RES"
"2","(7975,3675)","0","pure_quanta","I152";
;
PART_NUMBER"CS11002FB07"
PACK_TYPE"0402LF"
MATERIAL"CHIP"
VALUE"100"
WATTAGE"1/16W"
TOLERANCE"1%"
$LOCATION"R3180"
CDS_LIB"pure_quanta"
CDS_LOCATION"R3180"
$SEC"1"
CDS_SEC"1";
"A"
$PN"1"27;
"B"
$PN"2"10;
%"UNIVERSAL_GND"
"1","(300,-400)","0","logical_power","I16";
;
CDS_LIB"logical_power"
HDL_POWER"GND"
ROOM"IO_SLOT";
"A"13;
%"UNIVERSAL_GND"
"1","(4225,-700)","0","logical_power","I163";
;
CDS_LIB"logical_power"
HDL_POWER"GND"
ROOM"IO_SLOT";
"A"8;
%"UNIVERSAL_POWER"
"1","(4225,100)","0","logical_power","I164";
;
HDL_POWER"P3V3_OCP_V3_2"
CDS_LIB"logical_power";
"A"2;
%"Q_RES"
"1","(3675,-50)","0","pure_quanta","I165";
;
PART_NUMBER"CS21002FB06"
TOLERANCE"1%"
MATERIAL"CHIP"
VALUE"1K"
PACK_TYPE"0402LF"
WATTAGE"1/16W"
$LOCATION"R3173"
CDS_LIB"pure_quanta"
CDS_LOCATION"R3173"
$SEC"1"
CDS_SEC"1";
"B"
$PN"2"2;
"A"
$PN"1"92;
%"Q_CAP"
"1","(5725,-250)","0","pure_quanta","I166";
;
PART_NUMBER"CH6223MEA00"
VALUE"22UF"
MATERIAL"X6S"
TOLERANCE"20%"
VOLTAGE"16V"
PACK_TYPE"C0805"
$LOCATION"C1829"
CDS_LIB"pure_quanta"
CDS_LOCATION"C1829"
$SEC"1"
CDS_SEC"1";
"B"
$PN"2"14;
"A"
$PN"1"6;
%"Q_CAP"
"1","(6000,-250)","0","pure_quanta","I167";
;
PART_NUMBER"CH6223MEA00"
PACK_TYPE"C0805"
MATERIAL"X6S"
TOLERANCE"20%"
VOLTAGE"16V"
VALUE"22UF"
$LOCATION"C1830"
CDS_LIB"pure_quanta"
CDS_LOCATION"C1830"
$SEC"1"
CDS_SEC"1";
"B"
$PN"2"14;
"A"
$PN"1"6;
%"Q_CAP"
"1","(6400,-250)","0","pure_quanta","I168";
;
PART_NUMBER"CH4104K1B00"
PACK_TYPE"0402"
VOLTAGE"25V"
MATERIAL"X7R"
TOLERANCE"10%"
VALUE"0.1UF"
$LOCATION"C1831"
CDS_LIB"pure_quanta"
CDS_LOCATION"C1831"
$SEC"1"
CDS_SEC"1";
"B"
$PN"2"14;
"A"
$PN"1"6;
%"Q_CAP"
"1","(6950,-250)","0","pure_quanta","I169";
;
PART_NUMBER"CH4104K1B00"
PACK_TYPE"0402"
VALUE"0.1UF"
MATERIAL"X7R"
VOLTAGE"25V"
TOLERANCE"10%"
$LOCATION"C1833"
CDS_LIB"pure_quanta"
CDS_LOCATION"C1833"
$SEC"1"
CDS_SEC"1";
"B"
$PN"2"14;
"A"
$PN"1"6;
%"UNIVERSAL_POWER"
"1","(5725,100)","0","logical_power","I170";
;
HDL_POWER"P12V_OCP_V3_2"
CDS_LIB"logical_power";
"A"6;
%"Q_CAP"
"1","(7425,-250)","0","pure_quanta","I171";
;
PART_NUMBER"CH4104K1B00"
VOLTAGE"25V"
VALUE"0.1UF"
TOLERANCE"10%"
MATERIAL"X7R"
PACK_TYPE"0402"
$LOCATION"C1834"
CDS_LIB"pure_quanta"
CDS_LOCATION"C1834"
$SEC"1"
CDS_SEC"1";
"B"
$PN"2"14;
"A"
$PN"1"6;
%"UNIVERSAL_GND"
"1","(7425,-575)","0","logical_power","I172";
;
CDS_LIB"logical_power"
HDL_POWER"GND"
ROOM"IO_SLOT";
"A"14;
%"Q_CAP"
"1","(7925,-250)","0","pure_quanta","I173";
;
PART_NUMBER"CH4104K1B00"
VOLTAGE"25V"
TOLERANCE"10%"
PACK_TYPE"0402"
MATERIAL"X7R"
VALUE"0.1UF"
$LOCATION"C1835"
CDS_LIB"pure_quanta"
CDS_LOCATION"C1835"
$SEC"1"
CDS_SEC"1";
"B"
$PN"2"15;
"A"
$PN"1"3;
%"Q_CAP"
"1","(8175,-250)","0","pure_quanta","I174";
;
PART_NUMBER"CH4104K1B00"
MATERIAL"X7R"
TOLERANCE"10%"
VALUE"0.1UF"
PACK_TYPE"0402"
VOLTAGE"25V"
$LOCATION"C1836"
CDS_LIB"pure_quanta"
CDS_LOCATION"C1836"
$SEC"1"
CDS_SEC"1";
"B"
$PN"2"15;
"A"
$PN"1"3;
%"Q_CAP"
"1","(8450,-250)","0","pure_quanta","I175";
;
PART_NUMBER"CH4104K1B00"
PACK_TYPE"0402"
MATERIAL"X7R"
TOLERANCE"10%"
VOLTAGE"25V"
VALUE"0.1UF"
$LOCATION"C1837"
CDS_LIB"pure_quanta"
CDS_LOCATION"C1837"
$SEC"1"
CDS_SEC"1";
"B"
$PN"2"15;
"A"
$PN"1"3;
%"UNIVERSAL_GND"
"1","(8725,-575)","0","logical_power","I176";
;
CDS_LIB"logical_power"
HDL_POWER"GND"
ROOM"IO_SLOT";
"A"15;
%"Q_CAP"
"1","(8725,-250)","0","pure_quanta","I177";
;
PART_NUMBER"CH4104K1B00"
VOLTAGE"25V"
TOLERANCE"10%"
MATERIAL"X7R"
VALUE"0.1UF"
PACK_TYPE"0402"
$LOCATION"C1838"
CDS_LIB"pure_quanta"
CDS_LOCATION"C1838"
$SEC"1"
CDS_SEC"1";
"B"
$PN"2"15;
"A"
$PN"1"3;
%"UNIVERSAL_POWER"
"1","(7925,100)","0","logical_power","I178";
;
HDL_POWER"P3V3_OCP_V3_2"
CDS_LIB"logical_power";
"A"3;
%"Q_CAP"
"1","(6675,-250)","0","pure_quanta","I179";
;
PART_NUMBER"CH4104K1B00"
VALUE"0.1UF"
MATERIAL"X7R"
PACK_TYPE"0402"
VOLTAGE"25V"
TOLERANCE"10%"
$LOCATION"C1832"
CDS_LIB"pure_quanta"
CDS_LOCATION"C1832"
$SEC"1"
CDS_SEC"1";
"B"
$PN"2"14;
"A"
$PN"1"6;
%"Q_CAP"
"1","(7175,-250)","0","pure_quanta","I180";
;
PART_NUMBER"CH4104K1B00"
VALUE"0.1UF"
PACK_TYPE"0402"
TOLERANCE"10%"
MATERIAL"X7R"
VOLTAGE"25V"
$LOCATION"C1839"
CDS_LIB"pure_quanta"
CDS_LOCATION"C1839"
$SEC"1"
CDS_SEC"1";
"B"
$PN"2"14;
"A"
$PN"1"6;
%"TAP"
"1","(3275,2475)","2","standard","I188";
;
CDS_LIB"standard"
BODY_TYPE"PLUMBING"
HDL_TAP"TRUE";
"B \NAC \NWC"18;
"S \NAC"
BN"6"127;
%"TAP"
"1","(3125,2525)","2","standard","I189";
;
CDS_LIB"standard"
BODY_TYPE"PLUMBING"
HDL_TAP"TRUE";
"B \NAC \NWC"19;
"S \NAC"
BN"6"132;
%"UNIVERSAL_GND"
"1","(775,-400)","0","logical_power","I19";
;
CDS_LIB"logical_power"
HDL_POWER"GND"
ROOM"IO_SLOT";
"A"12;
%"TAP"
"1","(3125,2025)","2","standard","I191";
;
CDS_LIB"standard"
BODY_TYPE"PLUMBING"
HDL_TAP"TRUE";
"B \NAC \NWC"19;
"S \NAC"
BN"8"78;
%"TAP"
"1","(3275,3525)","2","standard","I194";
;
CDS_LIB"standard"
BODY_TYPE"PLUMBING"
HDL_TAP"TRUE";
"B \NAC \NWC"18;
"S \NAC"
BN"0"68;
%"TAP"
"1","(3125,3575)","2","standard","I196";
;
CDS_LIB"standard"
BODY_TYPE"PLUMBING"
HDL_TAP"TRUE";
"B \NAC \NWC"19;
"S \NAC"
BN"0"55;
%"TAP"
"1","(3275,3225)","2","standard","I198";
;
CDS_LIB"standard"
BODY_TYPE"PLUMBING"
HDL_TAP"TRUE";
"B \NAC \NWC"18;
"S \NAC"
BN"2"112;
%"TAP"
"1","(3125,3275)","2","standard","I199";
;
CDS_LIB"standard"
BODY_TYPE"PLUMBING"
HDL_TAP"TRUE";
"B \NAC \NWC"19;
"S \NAC"
BN"2"111;
%"Q_RES"
"2","(775,-175)","0","pure_quanta","I20";
;
PART_NUMBER"CS24702FB06"
PACK_TYPE"0402LF"
VALUE"4.7K"
WATTAGE"1/16W"
MATERIAL"CHIP"
TOLERANCE"1%"
$LOCATION"R3167"
CDS_LIB"pure_quanta"
CDS_LOCATION"R3167"
$SEC"1"
CDS_SEC"1";
"A"
$PN"1"61;
"B"
$PN"2"12;
%"TAP"
"1","(3125,2825)","2","standard","I201";
;
CDS_LIB"standard"
BODY_TYPE"PLUMBING"
HDL_TAP"TRUE";
"B \NAC \NWC"19;
"S \NAC"
BN"4"123;
%"TAP"
"1","(3275,2775)","2","standard","I203";
;
CDS_LIB"standard"
BODY_TYPE"PLUMBING"
HDL_TAP"TRUE";
"B \NAC \NWC"18;
"S \NAC"
BN"4"125;
%"TAP"
"1","(3275,1975)","2","standard","I208";
;
CDS_LIB"standard"
BODY_TYPE"PLUMBING"
HDL_TAP"TRUE";
"B \NAC \NWC"18;
"S \NAC"
BN"8"128;
%"TAP"
"1","(3275,1675)","2","standard","I210";
;
CDS_LIB"standard"
BODY_TYPE"PLUMBING"
HDL_TAP"TRUE";
"B \NAC \NWC"18;
"S \NAC"
BN"10"129;
%"TAP"
"1","(3125,1725)","2","standard","I212";
;
CDS_LIB"standard"
BODY_TYPE"PLUMBING"
HDL_TAP"TRUE";
"B \NAC \NWC"19;
"S \NAC"
BN"10"120;
%"TAP"
"1","(3275,1375)","2","standard","I213";
;
CDS_LIB"standard"
BODY_TYPE"PLUMBING"
HDL_TAP"TRUE";
"B \NAC \NWC"18;
"S \NAC"
BN"12"135;
%"TAP"
"1","(3125,1425)","2","standard","I214";
;
CDS_LIB"standard"
BODY_TYPE"PLUMBING"
HDL_TAP"TRUE";
"B \NAC \NWC"19;
"S \NAC"
BN"12"130;
%"TAP"
"1","(3275,1075)","2","standard","I216";
;
CDS_LIB"standard"
BODY_TYPE"PLUMBING"
HDL_TAP"TRUE";
"B \NAC \NWC"18;
"S \NAC"
BN"14"70;
%"TAP"
"1","(3125,1125)","2","standard","I218";
;
CDS_LIB"standard"
BODY_TYPE"PLUMBING"
HDL_TAP"TRUE";
"B \NAC \NWC"19;
"S \NAC"
BN"14"71;
%"TAP"
"1","(5775,3575)","0","standard","I224";
;
CDS_LIB"standard"
BODY_TYPE"PLUMBING"
HDL_TAP"TRUE";
"B \NAC \NWC"17;
"S \NAC"
BN"0"138;
%"TAP"
"1","(5775,3425)","0","standard","I225";
;
CDS_LIB"standard"
BODY_TYPE"PLUMBING"
HDL_TAP"TRUE";
"B \NAC \NWC"17;
"S \NAC"
BN"1"141;
%"TAP"
"1","(5775,3275)","0","standard","I226";
;
CDS_LIB"standard"
BODY_TYPE"PLUMBING"
HDL_TAP"TRUE";
"B \NAC \NWC"17;
"S \NAC"
BN"2"142;
%"TAP"
"1","(5775,3125)","0","standard","I227";
;
CDS_LIB"standard"
BODY_TYPE"PLUMBING"
HDL_TAP"TRUE";
"B \NAC \NWC"17;
"S \NAC"
BN"3"74;
%"TAP"
"1","(5775,2825)","0","standard","I228";
;
CDS_LIB"standard"
BODY_TYPE"PLUMBING"
HDL_TAP"TRUE";
"B \NAC \NWC"17;
"S \NAC"
BN"4"144;
%"TAP"
"1","(5775,2675)","0","standard","I229";
;
CDS_LIB"standard"
BODY_TYPE"PLUMBING"
HDL_TAP"TRUE";
"B \NAC \NWC"17;
"S \NAC"
BN"5"145;
%"Q_RES"
"2","(775,350)","0","pure_quanta","I23";
;
PART_NUMBER"CS24702FB06"
TOLERANCE"1%"
PACK_TYPE"0402LF"
MATERIAL"EMPTY"
WATTAGE"1/16W"
VALUE"4.7K"
$LOCATION"R3166"
CDS_LIB"pure_quanta"
CDS_LOCATION"R3166"
$SEC"1"
CDS_SEC"1";
"A"
$PN"1"1;
"B"
$PN"2"61;
%"TAP"
"1","(5625,3525)","0","standard","I230";
;
CDS_LIB"standard"
BODY_TYPE"PLUMBING"
HDL_TAP"TRUE";
"B \NAC \NWC"16;
"S \NAC"
BN"0"140;
%"TAP"
"1","(5625,3375)","0","standard","I231";
;
CDS_LIB"standard"
BODY_TYPE"PLUMBING"
HDL_TAP"TRUE";
"B \NAC \NWC"16;
"S \NAC"
BN"1"115;
%"TAP"
"1","(5625,3225)","0","standard","I232";
;
CDS_LIB"standard"
BODY_TYPE"PLUMBING"
HDL_TAP"TRUE";
"B \NAC \NWC"16;
"S \NAC"
BN"2"143;
%"TAP"
"1","(5625,3075)","0","standard","I233";
;
CDS_LIB"standard"
BODY_TYPE"PLUMBING"
HDL_TAP"TRUE";
"B \NAC \NWC"16;
"S \NAC"
BN"3"69;
%"TAP"
"1","(5625,2775)","0","standard","I234";
;
CDS_LIB"standard"
BODY_TYPE"PLUMBING"
HDL_TAP"TRUE";
"B \NAC \NWC"16;
"S \NAC"
BN"4"75;
%"TAP"
"1","(5775,2525)","0","standard","I235";
;
CDS_LIB"standard"
BODY_TYPE"PLUMBING"
HDL_TAP"TRUE";
"B \NAC \NWC"17;
"S \NAC"
BN"6"77;
%"TAP"
"1","(5775,2375)","0","standard","I236";
;
CDS_LIB"standard"
BODY_TYPE"PLUMBING"
HDL_TAP"TRUE";
"B \NAC \NWC"17;
"S \NAC"
BN"7"137;
%"TAP"
"1","(5775,2025)","0","standard","I237";
;
CDS_LIB"standard"
BODY_TYPE"PLUMBING"
HDL_TAP"TRUE";
"B \NAC \NWC"17;
"S \NAC"
BN"8"84;
%"TAP"
"1","(5775,1875)","0","standard","I238";
;
CDS_LIB"standard"
BODY_TYPE"PLUMBING"
HDL_TAP"TRUE";
"B \NAC \NWC"17;
"S \NAC"
BN"9"133;
%"TAP"
"1","(5775,1725)","0","standard","I239";
;
CDS_LIB"standard"
BODY_TYPE"PLUMBING"
HDL_TAP"TRUE";
"B \NAC \NWC"17;
"S \NAC"
BN"10"82;
%"UNIVERSAL_POWER"
"1","(300,650)","0","logical_power","I24";
;
HDL_POWER"P3V3_OCP_V3_2"
CDS_LIB"logical_power";
"A"1;
%"TAP"
"1","(5625,2625)","0","standard","I240";
;
CDS_LIB"standard"
BODY_TYPE"PLUMBING"
HDL_TAP"TRUE";
"B \NAC \NWC"16;
"S \NAC"
BN"5"76;
%"TAP"
"1","(5625,2475)","0","standard","I241";
;
CDS_LIB"standard"
BODY_TYPE"PLUMBING"
HDL_TAP"TRUE";
"B \NAC \NWC"16;
"S \NAC"
BN"6"146;
%"TAP"
"1","(5625,2325)","0","standard","I242";
;
CDS_LIB"standard"
BODY_TYPE"PLUMBING"
HDL_TAP"TRUE";
"B \NAC \NWC"16;
"S \NAC"
BN"7"136;
%"TAP"
"1","(5625,1975)","0","standard","I243";
;
CDS_LIB"standard"
BODY_TYPE"PLUMBING"
HDL_TAP"TRUE";
"B \NAC \NWC"16;
"S \NAC"
BN"8"147;
%"TAP"
"1","(5625,1825)","0","standard","I244";
;
CDS_LIB"standard"
BODY_TYPE"PLUMBING"
HDL_TAP"TRUE";
"B \NAC \NWC"16;
"S \NAC"
BN"9"81;
%"TAP"
"1","(5625,1675)","0","standard","I245";
;
CDS_LIB"standard"
BODY_TYPE"PLUMBING"
HDL_TAP"TRUE";
"B \NAC \NWC"16;
"S \NAC"
BN"10"91;
%"TAP"
"1","(5775,1575)","0","standard","I246";
;
CDS_LIB"standard"
BODY_TYPE"PLUMBING"
HDL_TAP"TRUE";
"B \NAC \NWC"17;
"S \NAC"
BN"11"90;
%"TAP"
"1","(5775,1425)","0","standard","I247";
;
CDS_LIB"standard"
BODY_TYPE"PLUMBING"
HDL_TAP"TRUE";
"B \NAC \NWC"17;
"S \NAC"
BN"12"60;
%"TAP"
"1","(5775,1275)","0","standard","I248";
;
CDS_LIB"standard"
BODY_TYPE"PLUMBING"
HDL_TAP"TRUE";
"B \NAC \NWC"17;
"S \NAC"
BN"13"79;
%"TAP"
"1","(5775,1125)","0","standard","I249";
;
CDS_LIB"standard"
BODY_TYPE"PLUMBING"
HDL_TAP"TRUE";
"B \NAC \NWC"17;
"S \NAC"
BN"14"33;
%"Q_RES"
"2","(300,-175)","0","pure_quanta","I25";
;
PART_NUMBER"CS24702FB06"
WATTAGE"1/16W"
MATERIAL"EMPTY"
PACK_TYPE"0402LF"
TOLERANCE"1%"
VALUE"4.7K"
$LOCATION"R3163"
CDS_LIB"pure_quanta"
CDS_LOCATION"R3163"
$SEC"1"
CDS_SEC"1";
"A"
$PN"1"62;
"B"
$PN"2"13;
%"TAP"
"1","(5775,975)","0","standard","I250";
;
CDS_LIB"standard"
BODY_TYPE"PLUMBING"
HDL_TAP"TRUE";
"B \NAC \NWC"17;
"S \NAC"
BN"15"86;
%"TAP"
"1","(5625,1525)","0","standard","I251";
;
CDS_LIB"standard"
BODY_TYPE"PLUMBING"
HDL_TAP"TRUE";
"B \NAC \NWC"16;
"S \NAC"
BN"11"59;
%"TAP"
"1","(5625,1375)","0","standard","I252";
;
CDS_LIB"standard"
BODY_TYPE"PLUMBING"
HDL_TAP"TRUE";
"B \NAC \NWC"16;
"S \NAC"
BN"12"134;
%"TAP"
"1","(5625,1225)","0","standard","I253";
;
CDS_LIB"standard"
BODY_TYPE"PLUMBING"
HDL_TAP"TRUE";
"B \NAC \NWC"16;
"S \NAC"
BN"13"80;
%"TAP"
"1","(5625,925)","0","standard","I254";
;
CDS_LIB"standard"
BODY_TYPE"PLUMBING"
HDL_TAP"TRUE";
"B \NAC \NWC"16;
"S \NAC"
BN"15"87;
%"TAP"
"1","(5625,1075)","0","standard","I255";
;
CDS_LIB"standard"
BODY_TYPE"PLUMBING"
HDL_TAP"TRUE";
"B \NAC \NWC"16;
"S \NAC"
BN"14"34;
%"UNIVERSAL_POWER"
"1","(3550,5500)","0","logical_power","I257";
;
HDL_POWER"P12V_OCP_V3_2"
CDS_LIB"logical_power";
"A"5;
%"Q_RES"
"2","(300,350)","0","pure_quanta","I26";
;
PART_NUMBER"CS24702FB06"
WATTAGE"1/16W"
VALUE"4.7K"
PACK_TYPE"0402LF"
MATERIAL"CHIP"
TOLERANCE"1%"
$LOCATION"R3162"
CDS_LIB"pure_quanta"
CDS_LOCATION"R3162"
$SEC"1"
CDS_SEC"1";
"A"
$PN"1"1;
"B"
$PN"2"62;
%"SCONN168_ME1016810202011"
"1","(4500,2800)","0","pure_quanta","I303";
;
PART_NUMBER"DFHSG8FR011"
VALUE"SCONN168_ME1016810202011"
MATERIAL"IO"
PART_TYPE"SMLF"
LOCATION"J35"
NEEDS_NO_SIZE"TRUE"
CDS_LMAN_SYM_OUTLINE"-500,2475,500,-2475"
CDS_LIB"pure_quanta"
$SEC"1"
CDS_SEC"1";
"G5"
$PN"G5"9;
"G4"
$PN"G4"9;
"G3"
$PN"G3"9;
"G2"
$PN"G2"9;
"G1"
$PN"G1"9;
"PRSNTB3# \B"
$PN"B70"63;
"RFU1_NC_B69"
$PN"B69"38;
"RFU1_NC_B68"
$PN"B68"37;
"GND_B67"
$PN"B67"11;
"PETP15"
$PN"B66"36;
"PETN15"
$PN"B65"35;
"GND_B64"
$PN"B64"11;
"PETP14"
$PN"B63"70;
"PETN14"
$PN"B62"71;
"GND_B61"
$PN"B61"11;
"PETP13"
$PN"B60"72;
"PETN13"
$PN"B59"73;
"GND_B58"
$PN"B58"11;
"PETP12"
$PN"B57"135;
"PWRBRK0# \B"
$PN"A70"57;
"USB_DATP"
$PN"A69"58;
"USB_DATN"
$PN"A68"83;
"GND_A67"
$PN"A67"9;
"PERP15"
$PN"A66"87;
"PERN15"
$PN"A65"86;
"GND_A64"
$PN"A64"9;
"PERP14"
$PN"A63"34;
"PERN14"
$PN"A62"33;
"GND_A61"
$PN"A61"9;
"PERP13"
$PN"A60"80;
"PERN13"
$PN"A59"79;
"GND_A58"
$PN"A58"9;
"PERP12"
$PN"A57"134;
"PERN12"
$PN"A56"60;
"GND_A55"
$PN"A55"9;
"PERP11"
$PN"A54"59;
"PERN11"
$PN"A53"90;
"GND_A52"
$PN"A52"9;
"PERP10"
$PN"A51"91;
"PERN10"
$PN"A50"82;
"GND_A49"
$PN"A49"9;
"PERP9"
$PN"A48"81;
"PERN9"
$PN"A47"133;
"GND_A46"
$PN"A46"9;
"PERP8"
$PN"A45"147;
"PERN8"
$PN"A44"84;
"GND_A43"
$PN"A43"9;
"PRSNTB1# \B"
$PN"A42"85;
"GND_A41"
$PN"A41"9;
"PERP7"
$PN"A40"136;
"PERN7"
$PN"A39"137;
"GND_A38"
$PN"A38"9;
"PERP6"
$PN"A37"146;
"PERN6"
$PN"A36"77;
"GND_A35"
$PN"A35"9;
"PERP5"
$PN"A34"76;
"PERN5"
$PN"A33"145;
"GND_A32"
$PN"A32"9;
"PERP4"
$PN"A31"75;
"PERN4"
$PN"A30"144;
"GND_A29"
$PN"A29"9;
"GND_A28"
$PN"A28"9;
"PERP3"
$PN"A27"69;
"PERN3"
$PN"A26"74;
"GND_A25"
$PN"A25"9;
"PERP2"
$PN"A24"143;
"PERN2"
$PN"A23"142;
"GND_A22"
$PN"A22"9;
"PERP1"
$PN"A21"115;
"PERN1"
$PN"A20"141;
"GND_A19"
$PN"A19"9;
"PERP0"
$PN"A18"140;
"PERN0"
$PN"A17"138;
"GND_A16"
$PN"A16"9;
"REFCLKP1"
$PN"A15"31;
"REFCLKN1"
$PN"A14"32;
"GND_A13"
$PN"A13"9;
"PRSNTB2# \B"
$PN"A12"29;
"PERST1# \B"
$PN"A11"28;
"PRSNTA# \B"
$PN"A10"27;
"SMRST# \B"
$PN"A9"24;
"SMDAT"
$PN"A8"26;
"SMCLK"
$PN"A7"25;
"GND_A6"
$PN"A6"9;
"GND_A5"
$PN"A5"9;
"GND_A4"
$PN"A4"9;
"GND_A3"
$PN"A3"9;
"GND_A2"
$PN"A2"9;
"GND_A1"
$PN"A1"9;
"RBT_CLK_IN"
$PN"OA14"21;
"GND_OA13"
$PN"OA13"9;
"REFCLKP3"
$PN"OA12"30;
"REFCLKN3"
$PN"OA11"20;
"GND_OA10"
$PN"OA10"9;
"RBT_TXD0"
$PN"OA9"52;
"RBT_TXD1"
$PN"OA8"53;
"RBT_TX_EN"
$PN"OA7"54;
"SLOT_ID1"
$PN"OA6"139;
"RBT_ARB_OUT"
$PN"OA5"106;
"RBT_ARB_IN"
$PN"OA4"107;
"WAKE# \B"
$PN"OA3"108;
"PERST3# \B"
$PN"OA2"109;
"PERST2# \B"
$PN"OA1"110;
"PETN12"
$PN"B56"130;
"GND_B55"
$PN"B55"11;
"PETP11"
$PN"B54"131;
"PETN11"
$PN"B53"119;
"GND_B52"
$PN"B52"11;
"PETP10"
$PN"B51"129;
"PETN10"
$PN"B50"120;
"GND_B49"
$PN"B49"11;
"PETP9"
$PN"B48"124;
"PETN9"
$PN"B47"121;
"GND_B46"
$PN"B46"11;
"PETP8"
$PN"B45"128;
"PETN8"
$PN"B44"78;
"GND_B43"
$PN"B43"11;
"PRSNTB0# \B"
$PN"B42"118;
"GND_B41"
$PN"B41"11;
"PETP7"
$PN"B40"117;
"PETN7"
$PN"B39"116;
"GND_B38"
$PN"B38"11;
"PETP6"
$PN"B37"127;
"PETN6"
$PN"B36"132;
"GND_B35"
$PN"B35"11;
"PETP5"
$PN"B34"126;
"PETN5"
$PN"B33"122;
"GND_B32"
$PN"B32"11;
"PETP4"
$PN"B31"125;
"PETN4"
$PN"B30"123;
"GND_B29"
$PN"B29"11;
"GND_B28"
$PN"B28"11;
"PETP3"
$PN"B27"64;
"PETN3"
$PN"B26"65;
"GND_B25"
$PN"B25"11;
"PETP2"
$PN"B24"112;
"PETN2"
$PN"B23"111;
"GND_B22"
$PN"B22"11;
"PETP1"
$PN"B21"66;
"PETN1"
$PN"B20"67;
"GND_B19"
$PN"B19"11;
"PETP0"
$PN"B18"68;
"PETN0"
$PN"B17"55;
"GND_B16"
$PN"B16"11;
"REFCLKP0"
$PN"B15"40;
"REFCLKN0"
$PN"B14"46;
"GND_B13"
$PN"B13"11;
"AUX_PWR_EN"
$PN"B12"43;
"+3.3V_EDGE"
$PN"B11"4;
"PERST0# \B"
$PN"B10"44;
"BIF2# \B"
$PN"B9"45;
"BIF1# \B"
$PN"B8"47;
"BIF0# \B"
$PN"B7"41;
"+12V_EDGE_B6"
$PN"B6"5;
"+12V_EDGE_B5"
$PN"B5"5;
"+12V_EDGE_B4"
$PN"B4"5;
"+12V_EDGE_B3"
$PN"B3"5;
"+12V_EDGE_B2"
$PN"B2"5;
"+12V_EDGE_B1"
$PN"B1"5;
"RBT_CRS_DV"
$PN"OB14"51;
"GND_OB13"
$PN"OB13"11;
"REFCLKP2"
$PN"OB12"50;
"REFCLKN2"
$PN"OB11"49;
"GND_OB10"
$PN"OB10"11;
"RBT_RXD0"
$PN"OB9"96;
"RBT_RXD1"
$PN"OB8"48;
"SLOT_ID0"
$PN"OB7"105;
"CLK"
$PN"OB6"97;
"DATA_OUT"
$PN"OB5"98;
"DATA_IN"
$PN"OB4"114;
"LD# \B"
$PN"OB3"99;
"MAIN_PWR_EN"
$PN"OB2"100;
"NIC_PWR_GOOD"
$PN"OB1"101;
%"TAP"
"1","(3275,975)","2","standard","I306";
;
CDS_LIB"standard"
BODY_TYPE"PLUMBING"
HDL_TAP"TRUE";
"B \NAC \NWC"18;
"S \NAC"
BN"15"35;
%"TAP"
"1","(3125,925)","2","standard","I307";
;
CDS_LIB"standard"
BODY_TYPE"PLUMBING"
HDL_TAP"TRUE";
"B \NAC \NWC"19;
"S \NAC"
BN"15"36;
%"TAP"
"1","(3275,1275)","2","standard","I309";
;
CDS_LIB"standard"
BODY_TYPE"PLUMBING"
HDL_TAP"TRUE";
"B \NAC \NWC"18;
"S \NAC"
BN"13"73;
%"Q_RES"
"1","(1975,3975)","0","pure_quanta","I31";
;
PART_NUMBER"CS00002JB13"
TOLERANCE"5%"
VALUE"0"
PACK_TYPE"0402LF"
$LOCATION"R3171"
CDS_LIB"pure_quanta"
MATERIAL"CHIP"
WATTAGE"1/16W"
CDS_LOCATION"R3171"
$SEC"1"
CDS_SEC"1";
"B"
$PN"2"45;
"A"
$PN"1"148;
%"TAP"
"1","(3125,1225)","2","standard","I310";
;
CDS_LIB"standard"
BODY_TYPE"PLUMBING"
HDL_TAP"TRUE";
"B \NAC \NWC"19;
"S \NAC"
BN"13"72;
%"TAP"
"1","(3275,1575)","2","standard","I312";
;
CDS_LIB"standard"
BODY_TYPE"PLUMBING"
HDL_TAP"TRUE";
"B \NAC \NWC"18;
"S \NAC"
BN"11"119;
%"TAP"
"1","(3125,1525)","2","standard","I313";
;
CDS_LIB"standard"
BODY_TYPE"PLUMBING"
HDL_TAP"TRUE";
"B \NAC \NWC"19;
"S \NAC"
BN"11"131;
%"TAP"
"1","(3125,1825)","2","standard","I315";
;
CDS_LIB"standard"
BODY_TYPE"PLUMBING"
HDL_TAP"TRUE";
"B \NAC \NWC"19;
"S \NAC"
BN"9"124;
%"TAP"
"1","(3275,1875)","2","standard","I316";
;
CDS_LIB"standard"
BODY_TYPE"PLUMBING"
HDL_TAP"TRUE";
"B \NAC \NWC"18;
"S \NAC"
BN"9"121;
%"TAP"
"1","(3275,2375)","2","standard","I318";
;
CDS_LIB"standard"
BODY_TYPE"PLUMBING"
HDL_TAP"TRUE";
"B \NAC \NWC"18;
"S \NAC"
BN"7"116;
%"TAP"
"1","(3125,2325)","2","standard","I319";
;
CDS_LIB"standard"
BODY_TYPE"PLUMBING"
HDL_TAP"TRUE";
"B \NAC \NWC"19;
"S \NAC"
BN"7"117;
%"Q_RES"
"1","(1975,4025)","0","pure_quanta","I32";
;
PART_NUMBER"CS00002JB13"
PACK_TYPE"0402LF"
TOLERANCE"5%"
VALUE"0"
$LOCATION"R3170"
WATTAGE"1/16W"
MATERIAL"CHIP"
CDS_LIB"pure_quanta"
CDS_LOCATION"R3170"
$SEC"1"
CDS_SEC"1";
"B"
$PN"2"47;
"A"
$PN"1"102;
%"TAP"
"1","(3275,2675)","2","standard","I321";
;
CDS_LIB"standard"
BODY_TYPE"PLUMBING"
HDL_TAP"TRUE";
"B \NAC \NWC"18;
"S \NAC"
BN"5"122;
%"TAP"
"1","(3125,2625)","2","standard","I322";
;
CDS_LIB"standard"
BODY_TYPE"PLUMBING"
HDL_TAP"TRUE";
"B \NAC \NWC"19;
"S \NAC"
BN"5"126;
%"TAP"
"1","(3275,3125)","2","standard","I324";
;
CDS_LIB"standard"
BODY_TYPE"PLUMBING"
HDL_TAP"TRUE";
"B \NAC \NWC"18;
"S \NAC"
BN"3"65;
%"TAP"
"1","(3125,3075)","2","standard","I325";
;
CDS_LIB"standard"
BODY_TYPE"PLUMBING"
HDL_TAP"TRUE";
"B \NAC \NWC"19;
"S \NAC"
BN"3"64;
%"TAP"
"1","(3275,3425)","2","standard","I327";
;
CDS_LIB"standard"
BODY_TYPE"PLUMBING"
HDL_TAP"TRUE";
"B \NAC \NWC"18;
"S \NAC"
BN"1"67;
%"TAP"
"1","(3125,3375)","2","standard","I328";
;
CDS_LIB"standard"
BODY_TYPE"PLUMBING"
HDL_TAP"TRUE";
"B \NAC \NWC"19;
"S \NAC"
BN"1"66;
%"Q_RES"
"1","(1975,4075)","0","pure_quanta","I33";
;
PART_NUMBER"CS00002JB13"
VALUE"0"
TOLERANCE"5%"
PACK_TYPE"0402LF"
MATERIAL"CHIP"
WATTAGE"1/16W"
$LOCATION"R3169"
CDS_LIB"pure_quanta"
CDS_LOCATION"R3169"
$SEC"1"
CDS_SEC"1";
"B"
$PN"2"41;
"A"
$PN"1"103;
%"Q_RES"
"1","(3675,-225)","0","pure_quanta","I333";
;
PART_NUMBER"CS31002FB08"
MATERIAL"CHIP"
VALUE"10K"
TOLERANCE"1%"
LOCATION"R3174"
CDS_LIB"pure_quanta"
PACK_TYPE"0402LF"
WATTAGE"1/16W"
$SEC"1"
CDS_SEC"1";
"B"
$PN"2"2;
"A"
$PN"1"93;
%"Q_RES"
"1","(3700,-575)","0","pure_quanta","I334";
;
PART_NUMBER"CS31002FB08"
MATERIAL"CHIP"
VALUE"10K"
TOLERANCE"1%"
LOCATION"R3175"
CDS_LIB"pure_quanta"
PACK_TYPE"0402LF"
WATTAGE"1/16W"
$SEC"1"
CDS_SEC"1";
"B"
$PN"2"8;
"A"
$PN"1"94;
%"Q_RES"
"1","(3700,-400)","0","pure_quanta","I336";
;
PART_NUMBER"CS21002FB06"
WATTAGE"1/16W"
MATERIAL"CHIP"
VALUE"1K"
TOLERANCE"1%"
PACK_TYPE"0402LF"
LOCATION"R3176"
CDS_LIB"pure_quanta"
$SEC"1"
CDS_SEC"1";
"B"
$PN"2"2;
"A"
$PN"1"95;
%"Q_RES"
"1","(6400,4025)","0","pure_quanta","I338";
;
PART_NUMBER"CS12002FB06"
TOLERANCE"1%"
WATTAGE"1/16W"
VALUE"200"
PACK_TYPE"0402LF"
MATERIAL"CHIP"
LOCATION"R3229"
CDS_LIB"pure_quanta"
LOCATION"R3229"
$SEC"1"
CDS_SEC"1";
"B"
$PN"2"23;
"A"
$PN"1"26;
%"Q_RES"
"1","(6400,4075)","0","pure_quanta","I339";
;
PART_NUMBER"CS12002FB06"
WATTAGE"1/16W"
PACK_TYPE"0402LF"
VALUE"200"
MATERIAL"CHIP"
TOLERANCE"1%"
LOCATION"R3228"
CDS_LIB"pure_quanta"
LOCATION"R3228"
$SEC"1"
CDS_SEC"1";
"B"
$PN"2"22;
"A"
$PN"1"25;
%"Q_RES"
"1","(1975,3825)","0","pure_quanta","I36";
;
PART_NUMBER"CS00002JB13"
VALUE"0"
TOLERANCE"5%"
PACK_TYPE"0402LF"
$LOCATION"R3172"
WATTAGE"1/16W"
MATERIAL"CHIP"
CDS_LIB"pure_quanta"
CDS_LOCATION"R3172"
$SEC"1"
CDS_SEC"1";
"B"
$PN"2"43;
"A"
$PN"1"42;
%"Q_RES"
"1","(750,2800)","0","pure_quanta","I37";
;
PART_NUMBER"CS31002FB08"
VALUE"10K"
MATERIAL"CHIP"
TOLERANCE"1%"
$LOCATION"R3165"
WATTAGE"1/16W"
PACK_TYPE"0402LF"
CDS_LIB"pure_quanta"
CDS_LOCATION"R3165"
$SEC"1"
CDS_SEC"1";
"B"
$PN"2"113;
"A"
$PN"1"7;
%"Q_RES"
"1","(750,2900)","0","pure_quanta","I38";
;
PART_NUMBER"CS31002FB08"
VALUE"10K"
TOLERANCE"1%"
WATTAGE"1/16W"
PACK_TYPE"0402LF"
MATERIAL"CHIP"
$LOCATION"R3164"
CDS_LIB"pure_quanta"
CDS_LOCATION"R3164"
$SEC"1"
CDS_SEC"1";
"B"
$PN"2"56;
"A"
$PN"1"7;
%"UNIVERSAL_GND"
"1","(325,2450)","0","logical_power","I42";
;
CDS_LIB"logical_power"
HDL_POWER"GND";
"A"7;
%"Q_RES"
"1","(800,2600)","0","pure_quanta","I43";
;
PART_NUMBER"CS41002FB09"
PACK_TYPE"0402LF"
MATERIAL"CHIP"
TOLERANCE"1%"
WATTAGE"1/16W"
VALUE"100K"
LOCATION"R413"
CDS_LIB"pure_quanta"
$SEC"1"
CDS_SEC"1";
"B"
$PN"2"39;
"A"
$PN"1"7;
%"Q_RES"
"1","(1975,5125)","0","pure_quanta","I5";
;
PART_NUMBER"CS00002JB13"
TOLERANCE"5%"
VALUE"0"
PACK_TYPE"0402LF"
$LOCATION"R3168"
MATERIAL"CHIP"
WATTAGE"1/16W"
CDS_LIB"pure_quanta"
CDS_LOCATION"R3168"
$SEC"1"
CDS_SEC"1";
"B"
$PN"2"100;
"A"
$PN"1"104;
%"UNIVERSAL_POWER"
"1","(2575,4275)","0","logical_power","I51";
;
HDL_POWER"P3V3_OCP_V3_2"
CDS_LIB"logical_power";
"A"4;
END.
